# T6G (Grand Teton) — schematic netlist excerpt (pin names and nets, part order shuffled) for the footprints in the layout excerpt that follows; sources: Cadence DE-HDL packaged netlist, KiCad conversion of 04192023_DAF0TMB3IC0_F0TG_MB_C_brd_V02_OCP.brd

D76  Q_LED  IC  pkg SMLF  page 255 : A = LED_PWRGD_PVDDCR_CPU1_P0_R ; C = LED_PWRGD_PVDDCR_CPU1_P0_D
R8115  Q_RES  5.11K 1% CHIP  pkg 0402LF  page 268 : A = P12V_AUX_UV_ADR_TRIGGER ; B = GND

(kicad_pcb
	(version 20260206)
	(generator "pcbnew")
	(generator_version "10.0")
	(general
		(thickness 1.6)
		(legacy_teardrops no)
	)
	(paper "A4")
	(title_block
		(title "04192023_DAF0TMB3IC0_F0TG_MB_C_brd_V02_OCP.brd")
		(comment 1 "Grand Teton / footprints 2690-2691 of 8354")
	)
	(layers
		(0 "F.Cu" signal "TOP")
		(4 "In1.Cu" signal "GND")
		(6 "In2.Cu" signal "IN1")
		(8 "In3.Cu" signal "GND1")
		(10 "In4.Cu" signal "IN2")
		(12 "In5.Cu" signal "GND2")
		(14 "In6.Cu" signal "IN3")
		(16 "In7.Cu" signal "GND3")
		(18 "In8.Cu" signal "VCC")
		(20 "In9.Cu" signal "VCC1")
		(22 "In10.Cu" signal "GND4")
		(24 "In11.Cu" signal "IN4")
		(26 "In12.Cu" signal "GND5")
		(28 "In13.Cu" signal "IN5")
		(30 "In14.Cu" signal "GND6")
		(32 "In15.Cu" signal "IN6")
		(34 "In16.Cu" signal "GND7")
		(2 "B.Cu" signal "BOTTOM")
		(9 "F.Adhes" user "F.Adhesive")
		(11 "B.Adhes" user "B.Adhesive")
		(13 "F.Paste" user "Package Geometry/Pastemask Top")
		(15 "B.Paste" user "Package Geometry/Pastemask Bottom")
		(5 "F.SilkS" user "Ref Des/Silkscreen Top")
		(7 "B.SilkS" user "Ref Des/Silkscreen Bottom")
		(1 "F.Mask" user "Board Geometry/Soldermask Top")
		(3 "B.Mask" user "Board Geometry/Soldermask Bottom")
		(17 "Dwgs.User" user "User.Drawings")
		(19 "Cmts.User" user "User.Comments")
		(21 "Eco1.User" user "User.Eco1")
		(23 "Eco2.User" user "User.Eco2")
		(25 "Edge.Cuts" user "Board Geometry/Outline")
		(27 "Margin" user)
		(31 "F.CrtYd" user "Package Geometry/Place Bound Top")
		(29 "B.CrtYd" user "Package Geometry/Place Bound Bottom")
		(35 "F.Fab" user "Ref Des/Assembly Top")
		(33 "B.Fab" user "Ref Des/Assembly Bottom")
	)
	(footprint ""
		(layer "F.Cu")
		(at 328.699876 -70.098412 90)
		(property "Reference" "D76"
			(at -3.934714 -0.691642 90)
			(unlocked yes)
			(layer "F.SilkS")
			(effects
				(font
					(size 0.7874 0.5842)
					(thickness 0.1524)
				)
				(justify left)
			)
		)
		(property "Value" ""
			(at 0 0 90)
			(layer "F.Fab")
			(effects
				(font
					(size 1.27 1.27)
				)
			)
		)
		(duplicate_pad_numbers_are_jumpers no)
		(fp_line
			(start 1.16078 -0.4826)
			(end 1.16078 0.4826)
			(stroke
				(width 0.1524)
				(type default)
			)
			(layer "F.SilkS")
		)
		(fp_line
			(start 1.03378 -0.4826)
			(end 1.03378 0.4826)
			(stroke
				(width 0.1524)
				(type default)
			)
			(layer "F.SilkS")
		)
		(fp_line
			(start 0.90678 -0.4826)
			(end 0.90678 0.4826)
			(stroke
				(width 0.1524)
				(type default)
			)
			(layer "F.SilkS")
		)
		(fp_line
			(start -0.64008 -0.4826)
			(end 1.16078 -0.4826)
			(stroke
				(width 0.1524)
				(type default)
			)
			(layer "F.SilkS")
		)
		(fp_line
			(start -0.79248 -0.4826)
			(end 1.03378 -0.4826)
			(stroke
				(width 0.1524)
				(type default)
			)
			(layer "F.SilkS")
		)
		(fp_line
			(start -0.89408 -0.4826)
			(end 0.90678 -0.4826)
			(stroke
				(width 0.1524)
				(type default)
			)
			(layer "F.SilkS")
		)
		(fp_line
			(start 1.16078 0.4826)
			(end -0.64008 0.4826)
			(stroke
				(width 0.1524)
				(type default)
			)
			(layer "F.SilkS")
		)
		(fp_line
			(start 1.03378 0.4826)
			(end -0.79248 0.4826)
			(stroke
				(width 0.1524)
				(type default)
			)
			(layer "F.SilkS")
		)
		(fp_line
			(start 0.90678 0.4826)
			(end -0.90678 0.4826)
			(stroke
				(width 0.1524)
				(type default)
			)
			(layer "F.SilkS")
		)
		(fp_line
			(start -0.90678 0.4826)
			(end -0.90678 -0.4699)
			(stroke
				(width 0.1524)
				(type default)
			)
			(layer "F.SilkS")
		)
		(fp_line
			(start 0.499872 -0.249936)
			(end 0.499872 0.249936)
			(stroke
				(width 0.1)
				(type default)
			)
			(layer "F.Fab")
		)
		(fp_line
			(start -0.499872 -0.249936)
			(end 0.499872 -0.249936)
			(stroke
				(width 0.1)
				(type default)
			)
			(layer "F.Fab")
		)
		(fp_line
			(start 0.499872 0.249936)
			(end -0.499872 0.249936)
			(stroke
				(width 0.1)
				(type default)
			)
			(layer "F.Fab")
		)
		(fp_line
			(start -0.499872 0.249936)
			(end -0.499872 -0.249936)
			(stroke
				(width 0.1)
				(type default)
			)
			(layer "F.Fab")
		)
		(pad "A" smd rect
			(at -0.47498 0 90)
			(size 0.6096 0.7112)
			(layers "F.Cu" "F.Mask" "F.Paste")
			(net "LED_PWRGD_PVDDCR_CPU1_P0_R")
		)
		(pad "C" smd rect
			(at 0.47498 0 90)
			(size 0.6096 0.7112)
			(layers "F.Cu" "F.Mask" "F.Paste")
			(net "LED_PWRGD_PVDDCR_CPU1_P0_D")
		)
	)
	(footprint ""
		(layer "F.Cu")
		(at 132.715 -109.474 -90)
		(property "Reference" "R8115"
			(at 0 0 270)
			(layer "F.SilkS")
			(hide yes)
			(effects
				(font
					(size 1.27 1.27)
				)
			)
		)
		(property "Value" ""
			(at 0 0 270)
			(layer "F.Fab")
			(effects
				(font
					(size 1.27 1.27)
				)
			)
		)
		(duplicate_pad_numbers_are_jumpers no)
		(fp_line
			(start -0.7874 0.4064)
			(end -0.7874 -0.4064)
			(stroke
				(width 0.1524)
				(type default)
			)
			(layer "F.SilkS")
		)
		(fp_line
			(start 0.7874 0.4064)
			(end -0.7874 0.4064)
			(stroke
				(width 0.1524)
				(type default)
			)
			(layer "F.SilkS")
		)
		(fp_line
			(start -0.7874 -0.4064)
			(end 0.7874 -0.4064)
			(stroke
				(width 0.1524)
				(type default)
			)
			(layer "F.SilkS")
		)
		(fp_line
			(start 0.7874 -0.4064)
			(end 0.7874 0.4064)
			(stroke
				(width 0.1524)
				(type default)
			)
			(layer "F.SilkS")
		)
		(fp_line
			(start -0.67945 0.3048)
			(end -0.67945 -0.305054)
			(stroke
				(width 0.1)
				(type default)
			)
			(layer "F.Fab")
		)
		(fp_line
			(start -0.12065 0.3048)
			(end -0.67945 0.3048)
			(stroke
				(width 0.1)
				(type default)
			)
			(layer "F.Fab")
		)
		(fp_line
			(start 0.120396 0.3048)
			(end 0.120396 0.2794)
			(stroke
				(width 0.1)
				(type default)
			)
			(layer "F.Fab")
		)
		(fp_line
			(start 0.67945 0.3048)
			(end 0.120396 0.3048)
			(stroke
				(width 0.1)
				(type default)
			)
			(layer "F.Fab")
		)
		(fp_line
			(start -0.12065 0.2794)
			(end -0.12065 0.3048)
			(stroke
				(width 0.1)
				(type default)
			)
			(layer "F.Fab")
		)
		(fp_line
			(start 0.120396 0.2794)
			(end -0.12065 0.2794)
			(stroke
				(width 0.1)
				(type default)
			)
			(layer "F.Fab")
		)
		(fp_line
			(start -0.12065 -0.2794)
			(end 0.12065 -0.2794)
			(stroke
				(width 0.1)
				(type default)
			)
			(layer "F.Fab")
		)
		(fp_line
			(start 0.12065 -0.2794)
			(end 0.12065 -0.3048)
			(stroke
				(width 0.1)
				(type default)
			)
			(layer "F.Fab")
		)
		(fp_line
			(start 0.12065 -0.3048)
			(end 0.67945 -0.3048)
			(stroke
				(width 0.1)
				(type default)
			)
			(layer "F.Fab")
		)
		(fp_line
			(start 0.67945 -0.3048)
			(end 0.67945 0.3048)
			(stroke
				(width 0.1)
				(type default)
			)
			(layer "F.Fab")
		)
		(fp_line
			(start -0.67945 -0.305054)
			(end -0.12065 -0.305054)
			(stroke
				(width 0.1)
				(type default)
			)
			(layer "F.Fab")
		)
		(fp_line
			(start -0.12065 -0.305054)
			(end -0.12065 -0.2794)
			(stroke
				(width 0.1)
				(type default)
			)
			(layer "F.Fab")
		)
		(pad "1" smd circle
			(at -0.40005 0 270)
			(size 0 0)
			(layers "F.Cu" "F.Mask" "F.Paste")
			(net "P12V_AUX_UV_ADR_TRIGGER")
		)
		(pad "2" smd circle
			(at 0.40005 0 270)
			(size 0 0)
			(layers "F.Cu" "F.Mask" "F.Paste")
			(net "GND")
		)
	)
)
